# T6G (Grand Teton) — schematic netlist excerpt (pin names and nets, part order shuffled) for the footprints in the layout excerpt that follows; sources: Cadence DE-HDL packaged netlist, KiCad conversion of 04192023_DAF0TMB3IC0_F0TG_MB_C_brd_V02_OCP.brd

PR6605  Q_RES  0 5% CHIP  pkg 0402LF  page 362 : A = P0V9_RETIMER_CPU0_VMON ; B = GND
R1205  Q_RES  0 5% CHIP  pkg 0402LF  page 28 : A = FM_PASSWORD_CLEAR_R_N ; B = FM_PASSWORD_CLEAR_N

(kicad_pcb
	(version 20260206)
	(generator "pcbnew")
	(generator_version "10.0")
	(general
		(thickness 1.6)
		(legacy_teardrops no)
	)
	(paper "A4")
	(title_block
		(title "04192023_DAF0TMB3IC0_F0TG_MB_C_brd_V02_OCP.brd")
		(comment 1 "Grand Teton / footprints 2356-2357 of 8354")
	)
	(layers
		(0 "F.Cu" signal "TOP")
		(4 "In1.Cu" signal "GND")
		(6 "In2.Cu" signal "IN1")
		(8 "In3.Cu" signal "GND1")
		(10 "In4.Cu" signal "IN2")
		(12 "In5.Cu" signal "GND2")
		(14 "In6.Cu" signal "IN3")
		(16 "In7.Cu" signal "GND3")
		(18 "In8.Cu" signal "VCC")
		(20 "In9.Cu" signal "VCC1")
		(22 "In10.Cu" signal "GND4")
		(24 "In11.Cu" signal "IN4")
		(26 "In12.Cu" signal "GND5")
		(28 "In13.Cu" signal "IN5")
		(30 "In14.Cu" signal "GND6")
		(32 "In15.Cu" signal "IN6")
		(34 "In16.Cu" signal "GND7")
		(2 "B.Cu" signal "BOTTOM")
		(9 "F.Adhes" user "F.Adhesive")
		(11 "B.Adhes" user "B.Adhesive")
		(13 "F.Paste" user "Package Geometry/Pastemask Top")
		(15 "B.Paste" user "Package Geometry/Pastemask Bottom")
		(5 "F.SilkS" user "Ref Des/Silkscreen Top")
		(7 "B.SilkS" user "Ref Des/Silkscreen Bottom")
		(1 "F.Mask" user "Board Geometry/Soldermask Top")
		(3 "B.Mask" user "Board Geometry/Soldermask Bottom")
		(17 "Dwgs.User" user "User.Drawings")
		(19 "Cmts.User" user "User.Comments")
		(21 "Eco1.User" user "User.Eco1")
		(23 "Eco2.User" user "User.Eco2")
		(25 "Edge.Cuts" user "Board Geometry/Outline")
		(27 "Margin" user)
		(31 "F.CrtYd" user "Package Geometry/Place Bound Top")
		(29 "B.CrtYd" user "Package Geometry/Place Bound Bottom")
		(35 "F.Fab" user "Ref Des/Assembly Top")
		(33 "B.Fab" user "Ref Des/Assembly Bottom")
	)
	(footprint ""
		(layer "F.Cu")
		(at 369.146836 -323.466968 90)
		(property "Reference" "R1205"
			(at 0 0 90)
			(layer "F.SilkS")
			(hide yes)
			(effects
				(font
					(size 1.27 1.27)
				)
			)
		)
		(property "Value" ""
			(at 0 0 90)
			(layer "F.Fab")
			(effects
				(font
					(size 1.27 1.27)
				)
			)
		)
		(duplicate_pad_numbers_are_jumpers no)
		(fp_line
			(start 0.7874 -0.4064)
			(end 0.7874 0.4064)
			(stroke
				(width 0.1524)
				(type default)
			)
			(layer "F.SilkS")
		)
		(fp_line
			(start -0.7874 -0.4064)
			(end 0.7874 -0.4064)
			(stroke
				(width 0.1524)
				(type default)
			)
			(layer "F.SilkS")
		)
		(fp_line
			(start 0.7874 0.4064)
			(end -0.7874 0.4064)
			(stroke
				(width 0.1524)
				(type default)
			)
			(layer "F.SilkS")
		)
		(fp_line
			(start -0.7874 0.4064)
			(end -0.7874 -0.4064)
			(stroke
				(width 0.1524)
				(type default)
			)
			(layer "F.SilkS")
		)
		(fp_line
			(start -0.12065 -0.305054)
			(end -0.12065 -0.2794)
			(stroke
				(width 0.1)
				(type default)
			)
			(layer "F.Fab")
		)
		(fp_line
			(start -0.67945 -0.305054)
			(end -0.12065 -0.305054)
			(stroke
				(width 0.1)
				(type default)
			)
			(layer "F.Fab")
		)
		(fp_line
			(start 0.67945 -0.3048)
			(end 0.67945 0.3048)
			(stroke
				(width 0.1)
				(type default)
			)
			(layer "F.Fab")
		)
		(fp_line
			(start 0.12065 -0.3048)
			(end 0.67945 -0.3048)
			(stroke
				(width 0.1)
				(type default)
			)
			(layer "F.Fab")
		)
		(fp_line
			(start 0.12065 -0.2794)
			(end 0.12065 -0.3048)
			(stroke
				(width 0.1)
				(type default)
			)
			(layer "F.Fab")
		)
		(fp_line
			(start -0.12065 -0.2794)
			(end 0.12065 -0.2794)
			(stroke
				(width 0.1)
				(type default)
			)
			(layer "F.Fab")
		)
		(fp_line
			(start 0.120396 0.2794)
			(end -0.12065 0.2794)
			(stroke
				(width 0.1)
				(type default)
			)
			(layer "F.Fab")
		)
		(fp_line
			(start -0.12065 0.2794)
			(end -0.12065 0.3048)
			(stroke
				(width 0.1)
				(type default)
			)
			(layer "F.Fab")
		)
		(fp_line
			(start 0.67945 0.3048)
			(end 0.120396 0.3048)
			(stroke
				(width 0.1)
				(type default)
			)
			(layer "F.Fab")
		)
		(fp_line
			(start 0.120396 0.3048)
			(end 0.120396 0.2794)
			(stroke
				(width 0.1)
				(type default)
			)
			(layer "F.Fab")
		)
		(fp_line
			(start -0.12065 0.3048)
			(end -0.67945 0.3048)
			(stroke
				(width 0.1)
				(type default)
			)
			(layer "F.Fab")
		)
		(fp_line
			(start -0.67945 0.3048)
			(end -0.67945 -0.305054)
			(stroke
				(width 0.1)
				(type default)
			)
			(layer "F.Fab")
		)
		(pad "1" smd circle
			(at -0.40005 0 90)
			(size 0 0)
			(layers "F.Cu" "F.Mask" "F.Paste")
			(net "FM_PASSWORD_CLEAR_R_N")
		)
		(pad "2" smd circle
			(at 0.40005 0 90)
			(size 0 0)
			(layers "F.Cu" "F.Mask" "F.Paste")
			(net "FM_PASSWORD_CLEAR_N")
		)
	)
	(footprint ""
		(layer "F.Cu")
		(at 449.551806 -424.310556)
		(property "Reference" "PR6605"
			(at 0 0 0)
			(layer "F.SilkS")
			(hide yes)
			(effects
				(font
					(size 1.27 1.27)
				)
			)
		)
		(property "Value" ""
			(at 0 0 0)
			(layer "F.Fab")
			(effects
				(font
					(size 1.27 1.27)
				)
			)
		)
		(duplicate_pad_numbers_are_jumpers no)
		(fp_line
			(start -0.7874 -0.4064)
			(end 0.7874 -0.4064)
			(stroke
				(width 0.1524)
				(type default)
			)
			(layer "F.SilkS")
		)
		(fp_line
			(start -0.7874 0.4064)
			(end -0.7874 -0.4064)
			(stroke
				(width 0.1524)
				(type default)
			)
			(layer "F.SilkS")
		)
		(fp_line
			(start 0.7874 -0.4064)
			(end 0.7874 0.4064)
			(stroke
				(width 0.1524)
				(type default)
			)
			(layer "F.SilkS")
		)
		(fp_line
			(start 0.7874 0.4064)
			(end -0.7874 0.4064)
			(stroke
				(width 0.1524)
				(type default)
			)
			(layer "F.SilkS")
		)
		(fp_line
			(start -0.67945 -0.305054)
			(end -0.12065 -0.305054)
			(stroke
				(width 0.1)
				(type default)
			)
			(layer "F.Fab")
		)
		(fp_line
			(start -0.67945 0.3048)
			(end -0.67945 -0.305054)
			(stroke
				(width 0.1)
				(type default)
			)
			(layer "F.Fab")
		)
		(fp_line
			(start -0.12065 -0.305054)
			(end -0.12065 -0.2794)
			(stroke
				(width 0.1)
				(type default)
			)
			(layer "F.Fab")
		)
		(fp_line
			(start -0.12065 -0.2794)
			(end 0.12065 -0.2794)
			(stroke
				(width 0.1)
				(type default)
			)
			(layer "F.Fab")
		)
		(fp_line
			(start -0.12065 0.2794)
			(end -0.12065 0.3048)
			(stroke
				(width 0.1)
				(type default)
			)
			(layer "F.Fab")
		)
		(fp_line
			(start -0.12065 0.3048)
			(end -0.67945 0.3048)
			(stroke
				(width 0.1)
				(type default)
			)
			(layer "F.Fab")
		)
		(fp_line
			(start 0.120396 0.2794)
			(end -0.12065 0.2794)
			(stroke
				(width 0.1)
				(type default)
			)
			(layer "F.Fab")
		)
		(fp_line
			(start 0.120396 0.3048)
			(end 0.120396 0.2794)
			(stroke
				(width 0.1)
				(type default)
			)
			(layer "F.Fab")
		)
		(fp_line
			(start 0.12065 -0.3048)
			(end 0.67945 -0.3048)
			(stroke
				(width 0.1)
				(type default)
			)
			(layer "F.Fab")
		)
		(fp_line
			(start 0.12065 -0.2794)
			(end 0.12065 -0.3048)
			(stroke
				(width 0.1)
				(type default)
			)
			(layer "F.Fab")
		)
		(fp_line
			(start 0.67945 -0.3048)
			(end 0.67945 0.3048)
			(stroke
				(width 0.1)
				(type default)
			)
			(layer "F.Fab")
		)
		(fp_line
			(start 0.67945 0.3048)
			(end 0.120396 0.3048)
			(stroke
				(width 0.1)
				(type default)
			)
			(layer "F.Fab")
		)
		(pad "1" smd circle
			(at -0.40005 0)
			(size 0 0)
			(layers "F.Cu" "F.Mask" "F.Paste")
			(net "P0V9_RETIMER_CPU0_VMON")
		)
		(pad "2" smd circle
			(at 0.40005 0)
			(size 0 0)
			(layers "F.Cu" "F.Mask" "F.Paste")
			(net "GND")
		)
	)
)
